# T6G (Grand Teton) — schematic netlist excerpt (pin names and nets, part order shuffled) for the footprints in the layout excerpt that follows; sources: Cadence DE-HDL packaged netlist, KiCad conversion of 04192023_DAF0TMB3IC0_F0TG_MB_C_brd_V02_OCP.brd

C1003  Q_CAP  0.1UF 10V 10% X7S  pkg C0201  page 312 : A = P1V8_CPU0_RT3_1A ; B = GND
C2225  Q_CAP  22UF 4V 20% X6S  pkg C0402  page 69 : A = PVDDCR_CPU1_P0 ; B = GND
R786  Q_RES  4.7K 5% EMPTY  pkg 0201LF  page 331 : A = P1V8_CPU1_RT_1D ; B = TEST1_RT_CPU1_P1

(kicad_pcb
	(version 20260206)
	(generator "pcbnew")
	(generator_version "10.0")
	(general
		(thickness 1.6)
		(legacy_teardrops no)
	)
	(paper "A4")
	(title_block
		(title "04192023_DAF0TMB3IC0_F0TG_MB_C_brd_V02_OCP.brd")
		(comment 1 "Grand Teton / footprints 7560-7562 of 8354")
	)
	(layers
		(0 "F.Cu" signal "TOP")
		(4 "In1.Cu" signal "GND")
		(6 "In2.Cu" signal "IN1")
		(8 "In3.Cu" signal "GND1")
		(10 "In4.Cu" signal "IN2")
		(12 "In5.Cu" signal "GND2")
		(14 "In6.Cu" signal "IN3")
		(16 "In7.Cu" signal "GND3")
		(18 "In8.Cu" signal "VCC")
		(20 "In9.Cu" signal "VCC1")
		(22 "In10.Cu" signal "GND4")
		(24 "In11.Cu" signal "IN4")
		(26 "In12.Cu" signal "GND5")
		(28 "In13.Cu" signal "IN5")
		(30 "In14.Cu" signal "GND6")
		(32 "In15.Cu" signal "IN6")
		(34 "In16.Cu" signal "GND7")
		(2 "B.Cu" signal "BOTTOM")
		(9 "F.Adhes" user "F.Adhesive")
		(11 "B.Adhes" user "B.Adhesive")
		(13 "F.Paste" user "Package Geometry/Pastemask Top")
		(15 "B.Paste" user "Package Geometry/Pastemask Bottom")
		(5 "F.SilkS" user "Ref Des/Silkscreen Top")
		(7 "B.SilkS" user "Ref Des/Silkscreen Bottom")
		(1 "F.Mask" user "Board Geometry/Soldermask Top")
		(3 "B.Mask" user "Board Geometry/Soldermask Bottom")
		(17 "Dwgs.User" user "User.Drawings")
		(19 "Cmts.User" user "User.Comments")
		(21 "Eco1.User" user "User.Eco1")
		(23 "Eco2.User" user "User.Eco2")
		(25 "Edge.Cuts" user "Board Geometry/Outline")
		(27 "Margin" user)
		(31 "F.CrtYd" user "Package Geometry/Place Bound Top")
		(29 "B.CrtYd" user "Package Geometry/Place Bound Bottom")
		(35 "F.Fab" user "Ref Des/Assembly Top")
		(33 "B.Fab" user "Ref Des/Assembly Bottom")
	)
	(footprint ""
		(layer "B.Cu")
		(at 380.078488 -395.148562 90)
		(property "Reference" "C1003"
			(at 0 0 90)
			(layer "B.SilkS")
			(hide yes)
			(effects
				(font
					(size 1.27 1.27)
				)
				(justify mirror)
			)
		)
		(property "Value" ""
			(at 0 0 90)
			(layer "B.Fab")
			(effects
				(font
					(size 1.27 1.27)
				)
				(justify mirror)
			)
		)
		(duplicate_pad_numbers_are_jumpers no)
		(fp_line
			(start 0.299974 -0.150114)
			(end -0.299974 -0.150114)
			(stroke
				(width 0.1)
				(type default)
			)
			(layer "B.Fab")
		)
		(fp_line
			(start -0.299974 -0.150114)
			(end -0.299974 0.150114)
			(stroke
				(width 0.1)
				(type default)
			)
			(layer "B.Fab")
		)
		(fp_line
			(start 0.299974 0.150114)
			(end 0.299974 -0.150114)
			(stroke
				(width 0.1)
				(type default)
			)
			(layer "B.Fab")
		)
		(fp_line
			(start -0.299974 0.150114)
			(end 0.299974 0.150114)
			(stroke
				(width 0.1)
				(type default)
			)
			(layer "B.Fab")
		)
		(pad "1" smd rect
			(at 0.2667 0 270)
			(size 0.3048 0.381)
			(layers "B.Cu" "B.Mask" "B.Paste")
			(net "P1V8_CPU0_RT3_1A")
		)
		(pad "2" smd rect
			(at -0.2667 0 270)
			(size 0.3048 0.381)
			(layers "B.Cu" "B.Mask" "B.Paste")
			(net "GND")
		)
	)
	(footprint ""
		(layer "B.Cu")
		(at 74.5236 -384.66268 180)
		(property "Reference" "R786"
			(at 0 0 0)
			(layer "B.SilkS")
			(hide yes)
			(effects
				(font
					(size 1.27 1.27)
				)
				(justify mirror)
			)
		)
		(property "Value" ""
			(at 0 0 0)
			(layer "B.Fab")
			(effects
				(font
					(size 1.27 1.27)
				)
				(justify mirror)
			)
		)
		(duplicate_pad_numbers_are_jumpers no)
		(fp_line
			(start 0.32512 0.175006)
			(end 0.32512 -0.175006)
			(stroke
				(width 0.1)
				(type default)
			)
			(layer "B.Fab")
		)
		(fp_line
			(start 0.32512 -0.175006)
			(end -0.32512 -0.175006)
			(stroke
				(width 0.1)
				(type default)
			)
			(layer "B.Fab")
		)
		(fp_line
			(start -0.32512 0.175006)
			(end 0.32512 0.175006)
			(stroke
				(width 0.1)
				(type default)
			)
			(layer "B.Fab")
		)
		(fp_line
			(start -0.32512 -0.175006)
			(end -0.32512 0.175006)
			(stroke
				(width 0.1)
				(type default)
			)
			(layer "B.Fab")
		)
		(pad "1" smd rect
			(at 0.2667 0)
			(size 0.3048 0.381)
			(layers "B.Cu" "B.Mask" "B.Paste")
			(net "P1V8_CPU1_RT_1D")
		)
		(pad "2" smd rect
			(at -0.2667 0 180)
			(size 0.3048 0.381)
			(layers "B.Cu" "B.Mask" "B.Paste")
			(net "TEST1_RT_CPU1_P1")
		)
	)
	(footprint ""
		(layer "B.Cu")
		(at 363.341158 -271.395952 180)
		(property "Reference" "C2225"
			(at 0 0 0)
			(layer "B.SilkS")
			(hide yes)
			(effects
				(font
					(size 1.27 1.27)
				)
				(justify mirror)
			)
		)
		(property "Value" ""
			(at 0 0 0)
			(layer "B.Fab")
			(effects
				(font
					(size 1.27 1.27)
				)
				(justify mirror)
			)
		)
		(duplicate_pad_numbers_are_jumpers no)
		(fp_line
			(start 0.7874 0.4064)
			(end 0.7874 -0.4064)
			(stroke
				(width 0.1524)
				(type default)
			)
			(layer "B.SilkS")
		)
		(fp_line
			(start 0.7874 -0.4064)
			(end -0.7874 -0.4064)
			(stroke
				(width 0.1524)
				(type default)
			)
			(layer "B.SilkS")
		)
		(fp_line
			(start -0.7874 0.4064)
			(end 0.7874 0.4064)
			(stroke
				(width 0.1524)
				(type default)
			)
			(layer "B.SilkS")
		)
		(fp_line
			(start -0.7874 -0.4064)
			(end -0.7874 0.4064)
			(stroke
				(width 0.1524)
				(type default)
			)
			(layer "B.SilkS")
		)
		(fp_line
			(start 0.67945 0.3048)
			(end 0.67945 -0.305054)
			(stroke
				(width 0.1)
				(type default)
			)
			(layer "B.Fab")
		)
		(fp_line
			(start 0.67945 -0.305054)
			(end 0.12065 -0.305054)
			(stroke
				(width 0.1)
				(type default)
			)
			(layer "B.Fab")
		)
		(fp_line
			(start 0.12065 0.3048)
			(end 0.67945 0.3048)
			(stroke
				(width 0.1)
				(type default)
			)
			(layer "B.Fab")
		)
		(fp_line
			(start 0.12065 0.2794)
			(end 0.12065 0.3048)
			(stroke
				(width 0.1)
				(type default)
			)
			(layer "B.Fab")
		)
		(fp_line
			(start 0.12065 -0.2794)
			(end -0.12065 -0.2794)
			(stroke
				(width 0.1)
				(type default)
			)
			(layer "B.Fab")
		)
		(fp_line
			(start 0.12065 -0.305054)
			(end 0.12065 -0.2794)
			(stroke
				(width 0.1)
				(type default)
			)
			(layer "B.Fab")
		)
		(fp_line
			(start -0.120396 0.3048)
			(end -0.120396 0.2794)
			(stroke
				(width 0.1)
				(type default)
			)
			(layer "B.Fab")
		)
		(fp_line
			(start -0.120396 0.2794)
			(end 0.12065 0.2794)
			(stroke
				(width 0.1)
				(type default)
			)
			(layer "B.Fab")
		)
		(fp_line
			(start -0.12065 -0.2794)
			(end -0.12065 -0.3048)
			(stroke
				(width 0.1)
				(type default)
			)
			(layer "B.Fab")
		)
		(fp_line
			(start -0.12065 -0.3048)
			(end -0.67945 -0.3048)
			(stroke
				(width 0.1)
				(type default)
			)
			(layer "B.Fab")
		)
		(fp_line
			(start -0.67945 0.3048)
			(end -0.120396 0.3048)
			(stroke
				(width 0.1)
				(type default)
			)
			(layer "B.Fab")
		)
		(fp_line
			(start -0.67945 -0.3048)
			(end -0.67945 0.3048)
			(stroke
				(width 0.1)
				(type default)
			)
			(layer "B.Fab")
		)
		(pad "1" smd circle
			(at 0.40005 0)
			(size 0 0)
			(layers "B.Cu" "B.Mask" "B.Paste")
			(net "PVDDCR_CPU1_P0")
		)
		(pad "2" smd circle
			(at -0.40005 0)
			(size 0 0)
			(layers "B.Cu" "B.Mask" "B.Paste")
			(net "GND")
		)
	)
)
